(kicad_pcb
	(version 20260206)
	(generator "pcbnew")
	(generator_version "10.0")
	(general
		(thickness 1.6)
		(legacy_teardrops no)
	)
	(paper "A4")
	(title_block
		(title "04192023_DAF0TMB3IC0_F0TG_MB_C_brd_V02_OCP.brd")
		(comment 1 "Grand Teton / footprints 2865-2868 of 8354")
	)
	(layers
		(0 "F.Cu" signal "TOP")
		(4 "In1.Cu" signal "GND")
		(6 "In2.Cu" signal "IN1")
		(8 "In3.Cu" signal "GND1")
		(10 "In4.Cu" signal "IN2")
		(12 "In5.Cu" signal "GND2")
		(14 "In6.Cu" signal "IN3")
		(16 "In7.Cu" signal "GND3")
		(18 "In8.Cu" signal "VCC")
		(20 "In9.Cu" signal "VCC1")
		(22 "In10.Cu" signal "GND4")
		(24 "In11.Cu" signal "IN4")
		(26 "In12.Cu" signal "GND5")
		(28 "In13.Cu" signal "IN5")
		(30 "In14.Cu" signal "GND6")
		(32 "In15.Cu" signal "IN6")
		(34 "In16.Cu" signal "GND7")
		(2 "B.Cu" signal "BOTTOM")
		(9 "F.Adhes" user "F.Adhesive")
		(11 "B.Adhes" user "B.Adhesive")
		(13 "F.Paste" user "Package Geometry/Pastemask Top")
		(15 "B.Paste" user "Package Geometry/Pastemask Bottom")
		(5 "F.SilkS" user "Ref Des/Silkscreen Top")
		(7 "B.SilkS" user "Ref Des/Silkscreen Bottom")
		(1 "F.Mask" user "Board Geometry/Soldermask Top")
		(3 "B.Mask" user "Board Geometry/Soldermask Bottom")
		(17 "Dwgs.User" user "User.Drawings")
		(19 "Cmts.User" user "User.Comments")
		(21 "Eco1.User" user "User.Eco1")
		(23 "Eco2.User" user "User.Eco2")
		(25 "Edge.Cuts" user "Board Geometry/Outline")
		(27 "Margin" user)
		(31 "F.CrtYd" user "Package Geometry/Place Bound Top")
		(29 "B.CrtYd" user "Package Geometry/Place Bound Bottom")
		(35 "F.Fab" user "Ref Des/Assembly Top")
		(33 "B.Fab" user "Ref Des/Assembly Bottom")
	)
	(footprint ""
		(layer "F.Cu")
		(at 82.706718 -21.016722 90)
		(property "Reference" "R3816"
			(at 0 0 90)
			(layer "F.SilkS")
			(hide yes)
			(effects
				(font
					(size 1.27 1.27)
				)
			)
		)
		(property "Value" ""
			(at 0 0 90)
			(layer "F.Fab")
			(effects
				(font
					(size 1.27 1.27)
				)
			)
		)
		(duplicate_pad_numbers_are_jumpers no)
		(fp_line
			(start 0.7874 -0.4064)
			(end 0.7874 0.4064)
			(stroke
				(width 0.1524)
				(type default)
			)
			(layer "F.SilkS")
		)
		(fp_line
			(start -0.7874 -0.4064)
			(end 0.7874 -0.4064)
			(stroke
				(width 0.1524)
				(type default)
			)
			(layer "F.SilkS")
		)
		(fp_line
			(start 0.7874 0.4064)
			(end -0.7874 0.4064)
			(stroke
				(width 0.1524)
				(type default)
			)
			(layer "F.SilkS")
		)
		(fp_line
			(start -0.7874 0.4064)
			(end -0.7874 -0.4064)
			(stroke
				(width 0.1524)
				(type default)
			)
			(layer "F.SilkS")
		)
		(fp_line
			(start -0.12065 -0.305054)
			(end -0.12065 -0.2794)
			(stroke
				(width 0.1)
				(type default)
			)
			(layer "F.Fab")
		)
		(fp_line
			(start -0.67945 -0.305054)
			(end -0.12065 -0.305054)
			(stroke
				(width 0.1)
				(type default)
			)
			(layer "F.Fab")
		)
		(fp_line
			(start 0.67945 -0.3048)
			(end 0.67945 0.3048)
			(stroke
				(width 0.1)
				(type default)
			)
			(layer "F.Fab")
		)
		(fp_line
			(start 0.12065 -0.3048)
			(end 0.67945 -0.3048)
			(stroke
				(width 0.1)
				(type default)
			)
			(layer "F.Fab")
		)
		(fp_line
			(start 0.12065 -0.2794)
			(end 0.12065 -0.3048)
			(stroke
				(width 0.1)
				(type default)
			)
			(layer "F.Fab")
		)
		(fp_line
			(start -0.12065 -0.2794)
			(end 0.12065 -0.2794)
			(stroke
				(width 0.1)
				(type default)
			)
			(layer "F.Fab")
		)
		(fp_line
			(start 0.120396 0.2794)
			(end -0.12065 0.2794)
			(stroke
				(width 0.1)
				(type default)
			)
			(layer "F.Fab")
		)
		(fp_line
			(start -0.12065 0.2794)
			(end -0.12065 0.3048)
			(stroke
				(width 0.1)
				(type default)
			)
			(layer "F.Fab")
		)
		(fp_line
			(start 0.67945 0.3048)
			(end 0.120396 0.3048)
			(stroke
				(width 0.1)
				(type default)
			)
			(layer "F.Fab")
		)
		(fp_line
			(start 0.120396 0.3048)
			(end 0.120396 0.2794)
			(stroke
				(width 0.1)
				(type default)
			)
			(layer "F.Fab")
		)
		(fp_line
			(start -0.12065 0.3048)
			(end -0.67945 0.3048)
			(stroke
				(width 0.1)
				(type default)
			)
			(layer "F.Fab")
		)
		(fp_line
			(start -0.67945 0.3048)
			(end -0.67945 -0.305054)
			(stroke
				(width 0.1)
				(type default)
			)
			(layer "F.Fab")
		)
		(pad "1" smd circle
			(at -0.40005 0 90)
			(size 0 0)
			(layers "F.Cu" "F.Mask" "F.Paste")
			(net "P3V3_AUX")
		)
		(pad "2" smd circle
			(at 0.40005 0 90)
			(size 0 0)
			(layers "F.Cu" "F.Mask" "F.Paste")
			(net "P12V_OCP_FAULT_2")
		)
	)
	(footprint ""
		(layer "F.Cu")
		(at 210.204558 -401.920202 180)
		(property "Reference" "PU288"
			(at 2.820924 -5.00888 90)
			(unlocked yes)
			(layer "F.SilkS")
			(effects
				(font
					(size 0.7874 0.5842)
					(thickness 0.1524)
				)
			)
		)
		(property "Value" ""
			(at 0 0 180)
			(layer "F.Fab")
			(effects
				(font
					(size 1.27 1.27)
				)
			)
		)
		(duplicate_pad_numbers_are_jumpers no)
		(fp_line
			(start 2.567686 2.567686)
			(end 2.567686 -2.567686)
			(stroke
				(width 0.1524)
				(type default)
			)
			(layer "F.SilkS")
		)
		(fp_line
			(start 2.567686 -2.567686)
			(end -2.567686 -2.567686)
			(stroke
				(width 0.1524)
				(type default)
			)
			(layer "F.SilkS")
		)
		(fp_line
			(start -2.567686 2.567686)
			(end 2.567686 2.567686)
			(stroke
				(width 0.1524)
				(type default)
			)
			(layer "F.SilkS")
		)
		(fp_line
			(start -2.567686 -2.567686)
			(end -2.567686 2.567686)
			(stroke
				(width 0.1524)
				(type default)
			)
			(layer "F.SilkS")
		)
		(fp_poly
			(pts
				(xy -2.632456 -2.13233) (xy -3.709924 -2.491486) (xy -2.991612 -3.209798)
			)
			(stroke
				(width 0)
				(type default)
			)
			(fill yes)
			(layer "F.SilkS")
		)
		(fp_line
			(start 2.549906 2.549906)
			(end 2.549906 -2.549906)
			(stroke
				(width 0.1)
				(type default)
			)
			(layer "F.Fab")
		)
		(fp_line
			(start 2.549906 -2.549906)
			(end -2.549906 -2.549906)
			(stroke
				(width 0.1)
				(type default)
			)
			(layer "F.Fab")
		)
		(fp_line
			(start -2.549906 2.549906)
			(end 2.549906 2.549906)
			(stroke
				(width 0.1)
				(type default)
			)
			(layer "F.Fab")
		)
		(fp_line
			(start -2.549906 -2.549906)
			(end -2.549906 2.549906)
			(stroke
				(width 0.1)
				(type default)
			)
			(layer "F.Fab")
		)
		(fp_poly
			(pts
				(xy -3.806698 -2.25806) (xy -3.806698 -1.24206) (xy -2.790698 -1.75006)
			)
			(stroke
				(width 0)
				(type default)
			)
			(fill yes)
			(layer "F.Fab")
		)
		(pad "1" smd rect
			(at -2.250186 -1.75006 270)
			(size 0.254 0.3556)
			(layers "F.Cu" "F.Mask" "F.Paste")
			(net "P12V_AUX")
		)
		(pad "2" smd rect
			(at -2.237486 -1.249934 270)
			(size 0.254 0.381)
			(layers "F.Cu" "F.Mask" "F.Paste")
			(net "P12V_AUX")
		)
		(pad "3" smd rect
			(at -2.237486 -0.750062 270)
			(size 0.254 0.381)
			(layers "F.Cu" "F.Mask" "F.Paste")
			(net "HSC_D_OC_2")
		)
		(pad "4" smd rect
			(at -2.237486 -0.249936 270)
			(size 0.254 0.381)
			(layers "F.Cu" "F.Mask" "F.Paste")
			(net "HSC_ON")
		)
		(pad "5" smd rect
			(at -2.237486 0.249936 270)
			(size 0.254 0.381)
			(layers "F.Cu" "F.Mask" "F.Paste")
			(net "HSC_FAULT")
		)
		(pad "6" smd rect
			(at -2.237486 0.750062 270)
			(size 0.254 0.381)
			(layers "F.Cu" "F.Mask" "F.Paste")
			(net "HSC_FLT_TYPE_2")
		)
		(pad "7" smd rect
			(at -2.237486 1.249934 270)
			(size 0.254 0.381)
			(layers "F.Cu" "F.Mask" "F.Paste")
			(net "HSC_NC1_2")
		)
		(pad "8" smd rect
			(at -2.250186 1.75006 270)
			(size 0.254 0.3556)
			(layers "F.Cu" "F.Mask" "F.Paste")
			(net "HSC_MODE_2")
		)
		(pad "9" smd rect
			(at -1.75006 2.250186 180)
			(size 0.254 0.3556)
			(layers "F.Cu" "F.Mask" "F.Paste")
			(net "P12V_PSU")
		)
		(pad "10" smd rect
			(at -1.249934 2.237486 180)
			(size 0.254 0.381)
			(layers "F.Cu" "F.Mask" "F.Paste")
			(net "P12V_PSU")
		)
		(pad "11" smd rect
			(at -0.750062 2.237486 180)
			(size 0.254 0.381)
			(layers "F.Cu" "F.Mask" "F.Paste")
			(net "P12V_PSU")
		)
		(pad "12" smd rect
			(at -0.249936 2.237486 180)
			(size 0.254 0.381)
			(layers "F.Cu" "F.Mask" "F.Paste")
			(net "P12V_PSU")
		)
		(pad "13" smd rect
			(at 0.249936 2.237486 180)
			(size 0.254 0.381)
			(layers "F.Cu" "F.Mask" "F.Paste")
			(net "P12V_PSU")
		)
		(pad "14" smd rect
			(at 0.750062 2.237486 180)
			(size 0.254 0.381)
			(layers "F.Cu" "F.Mask" "F.Paste")
			(net "P12V_PSU")
		)
		(pad "15" smd rect
			(at 1.249934 2.237486 180)
			(size 0.254 0.381)
			(layers "F.Cu" "F.Mask" "F.Paste")
			(net "P12V_PSU")
		)
		(pad "16" smd rect
			(at 1.75006 2.250186 180)
			(size 0.254 0.3556)
			(layers "F.Cu" "F.Mask" "F.Paste")
			(net "P12V_PSU")
		)
		(pad "17" smd rect
			(at 2.250186 1.75006 270)
			(size 0.254 0.3556)
			(layers "F.Cu" "F.Mask" "F.Paste")
			(net "HSC_SCREF_2")
		)
		(pad "18" smd rect
			(at 2.237486 1.249934 270)
			(size 0.254 0.381)
			(layers "F.Cu" "F.Mask" "F.Paste")
			(net "HSC_VTEMP")
		)
		(pad "19" smd rect
			(at 2.237486 0.750062 270)
			(size 0.254 0.381)
			(layers "F.Cu" "F.Mask" "F.Paste")
			(net "HSC_SS")
		)
		(pad "20" smd rect
			(at 2.237486 0.249936 270)
			(size 0.254 0.381)
			(layers "F.Cu" "F.Mask" "F.Paste")
			(net "AGND_HSC")
		)
		(pad "21" smd rect
			(at 2.237486 -0.249936 270)
			(size 0.254 0.381)
			(layers "F.Cu" "F.Mask" "F.Paste")
			(net "HSC_VDD_R_2")
		)
		(pad "22" smd rect
			(at 2.237486 -0.750062 270)
			(size 0.254 0.381)
			(layers "F.Cu" "F.Mask" "F.Paste")
			(net "HSC_IMON")
		)
		(pad "23" smd rect
			(at 2.237486 -1.249934 270)
			(size 0.254 0.381)
			(layers "F.Cu" "F.Mask" "F.Paste")
			(net "HSC_CS_2")
		)
		(pad "24" smd rect
			(at 2.250186 -1.75006 270)
			(size 0.254 0.3556)
			(layers "F.Cu" "F.Mask" "F.Paste")
			(net "HSC_OCREF")
		)
		(pad "25" smd rect
			(at 1.75006 -2.250186 180)
			(size 0.254 0.3556)
			(layers "F.Cu" "F.Mask" "F.Paste")
			(net "P12V_AUX")
		)
		(pad "26" smd rect
			(at 1.249934 -2.237486 180)
			(size 0.254 0.381)
			(layers "F.Cu" "F.Mask" "F.Paste")
			(net "P12V_AUX")
		)
		(pad "27" smd rect
			(at 0.750062 -2.237486 180)
			(size 0.254 0.381)
			(layers "F.Cu" "F.Mask" "F.Paste")
			(net "P12V_AUX")
		)
		(pad "28" smd rect
			(at 0.249936 -2.237486 180)
			(size 0.254 0.381)
			(layers "F.Cu" "F.Mask" "F.Paste")
			(net "P12V_AUX")
		)
		(pad "29" smd rect
			(at -0.249936 -2.237486 180)
			(size 0.254 0.381)
			(layers "F.Cu" "F.Mask" "F.Paste")
			(net "P12V_AUX")
		)
		(pad "30" smd rect
			(at -0.750062 -2.237486 180)
			(size 0.254 0.381)
			(layers "F.Cu" "F.Mask" "F.Paste")
			(net "P12V_AUX")
		)
		(pad "31" smd rect
			(at -1.249934 -2.237486 180)
			(size 0.254 0.381)
			(layers "F.Cu" "F.Mask" "F.Paste")
			(net "P12V_AUX")
		)
		(pad "32" smd rect
			(at -1.75006 -2.250186 180)
			(size 0.254 0.3556)
			(layers "F.Cu" "F.Mask" "F.Paste")
			(net "P12V_AUX")
		)
		(pad "33" smd rect
			(at 0 0 180)
			(size 3.4036 3.4036)
			(layers "F.Cu" "F.Mask" "F.Paste")
			(net "P12V_PSU")
		)
		(zone
			(layer "F.Cu")
			(hatch none 0.5)
			(connect_pads
				(clearance 0)
			)
			(min_thickness 0.25)
			(keepout
				(tracks not_allowed)
				(vias allowed)
				(pads allowed)
				(copperpour not_allowed)
				(footprints allowed)
			)
			(placement
				(enabled no)
				(sheetname "")
			)
			(fill
				(thermal_gap 0.5)
				(thermal_bridge_width 0.5)
				(island_removal_mode 0)
			)
			(polygon
				(pts
					(xy 208.182972 -403.58822) (xy 208.451958 -403.58822) (xy 208.451958 -400.167602) (xy 211.957158 -400.167602)
					(xy 211.957158 -402.428202) (xy 212.200744 -402.428202) (xy 212.200744 -400.472402) (xy 212.226144 -400.472402)
					(xy 212.226144 -399.898616) (xy 211.652358 -399.898616) (xy 211.652358 -399.924016) (xy 208.756758 -399.924016)
					(xy 208.756758 -399.898616) (xy 208.182972 -399.898616) (xy 208.182972 -400.472402) (xy 208.208372 -400.472402)
					(xy 208.208372 -403.368002) (xy 208.182972 -403.368002)
				)
			)
		)
	)
	(footprint ""
		(layer "F.Cu")
		(at 288.970212 -426.357542)
		(property "Reference" "U176"
			(at -0.771906 -2.687574 0)
			(unlocked yes)
			(layer "F.SilkS")
			(effects
				(font
					(size 0.7874 0.5842)
					(thickness 0.1524)
				)
				(justify left)
			)
		)
		(property "Value" ""
			(at 0 0 0)
			(layer "F.Fab")
			(effects
				(font
					(size 1.27 1.27)
				)
			)
		)
		(duplicate_pad_numbers_are_jumpers no)
		(fp_line
			(start -1.3716 -1.524)
			(end -0.508 -1.524)
			(stroke
				(width 0.1524)
				(type default)
			)
			(layer "F.SilkS")
		)
		(fp_line
			(start -1.3716 1.524)
			(end -1.3716 -1.524)
			(stroke
				(width 0.1524)
				(type default)
			)
			(layer "F.SilkS")
		)
		(fp_line
			(start -0.508 -1.524)
			(end 0 -1.016)
			(stroke
				(width 0.1524)
				(type default)
			)
			(layer "F.SilkS")
		)
		(fp_line
			(start 0 -1.016)
			(end 0.508 -1.524)
			(stroke
				(width 0.1524)
				(type default)
			)
			(layer "F.SilkS")
		)
		(fp_line
			(start 0.508 -1.524)
			(end 1.3716 -1.524)
			(stroke
				(width 0.1524)
				(type default)
			)
			(layer "F.SilkS")
		)
		(fp_line
			(start 1.3716 -1.524)
			(end 1.3716 1.524)
			(stroke
				(width 0.1524)
				(type default)
			)
			(layer "F.SilkS")
		)
		(fp_line
			(start 1.3716 1.524)
			(end -1.3716 1.524)
			(stroke
				(width 0.1524)
				(type default)
			)
			(layer "F.SilkS")
		)
		(fp_poly
			(pts
				(xy -2.082292 -2.04724) (xy -1.457452 -2.04724) (xy -1.78562 -1.49352)
			)
			(stroke
				(width 0)
				(type default)
			)
			(fill yes)
			(layer "F.SilkS")
		)
		(fp_line
			(start -2.54 -1.0668)
			(end -1.5494 -1.0668)
			(stroke
				(width 0.1)
				(type default)
			)
			(layer "F.Fab")
		)
		(fp_line
			(start -2.54 1.0668)
			(end -2.54 -1.0668)
			(stroke
				(width 0.1)
				(type default)
			)
			(layer "F.Fab")
		)
		(fp_line
			(start -1.5494 -1.524)
			(end 1.5494 -1.524)
			(stroke
				(width 0.1)
				(type default)
			)
			(layer "F.Fab")
		)
		(fp_line
			(start -1.5494 -1.0668)
			(end -1.5494 -1.524)
			(stroke
				(width 0.1)
				(type default)
			)
			(layer "F.Fab")
		)
		(fp_line
			(start -1.5494 1.0668)
			(end -2.54 1.0668)
			(stroke
				(width 0.1)
				(type default)
			)
			(layer "F.Fab")
		)
		(fp_line
			(start -1.5494 1.0668)
			(end -1.5494 -1.0668)
			(stroke
				(width 0.1)
				(type default)
			)
			(layer "F.Fab")
		)
		(fp_line
			(start -1.5494 1.524)
			(end -1.5494 1.0668)
			(stroke
				(width 0.1)
				(type default)
			)
			(layer "F.Fab")
		)
		(fp_line
			(start 1.5494 -1.524)
			(end 1.5494 -1.0668)
			(stroke
				(width 0.1)
				(type default)
			)
			(layer "F.Fab")
		)
		(fp_line
			(start 1.5494 -1.0668)
			(end 1.5494 1.0668)
			(stroke
				(width 0.1)
				(type default)
			)
			(layer "F.Fab")
		)
		(fp_line
			(start 1.5494 -1.0668)
			(end 2.54 -1.0668)
			(stroke
				(width 0.1)
				(type default)
			)
			(layer "F.Fab")
		)
		(fp_line
			(start 1.5494 1.0668)
			(end 1.5494 1.524)
			(stroke
				(width 0.1)
				(type default)
			)
			(layer "F.Fab")
		)
		(fp_line
			(start 1.5494 1.524)
			(end -1.5494 1.524)
			(stroke
				(width 0.1)
				(type default)
			)
			(layer "F.Fab")
		)
		(fp_line
			(start 2.54 -1.0668)
			(end 2.54 1.0668)
			(stroke
				(width 0.1)
				(type default)
			)
			(layer "F.Fab")
		)
		(fp_line
			(start 2.54 1.0668)
			(end 1.5494 1.0668)
			(stroke
				(width 0.1)
				(type default)
			)
			(layer "F.Fab")
		)
		(fp_poly
			(pts
				(xy -3.60172 -0.719328) (xy -3.60172 -1.344168) (xy -3.048 -1.016)
			)
			(stroke
				(width 0)
				(type default)
			)
			(fill yes)
			(layer "F.Fab")
		)
		(pad "1" smd rect
			(at -2.232406 -0.975106 270)
			(size 0.3556 1.4224)
			(layers "F.Cu" "F.Mask" "F.Paste")
			(net "SMB_BMC_SWB_EN_R2")
		)
		(pad "2" smd rect
			(at -2.232406 -0.32512 270)
			(size 0.3556 1.4224)
			(layers "F.Cu" "F.Mask" "F.Paste")
			(net "I3C_BMC_SWB_BUF_R_SCL")
		)
		(pad "3" smd rect
			(at -2.232406 0.32512 270)
			(size 0.3556 1.4224)
			(layers "F.Cu" "F.Mask" "F.Paste")
			(net "I3C_BMC_SWB_R_SCL")
		)
		(pad "4" smd rect
			(at -2.232406 0.975106 270)
			(size 0.3556 1.4224)
			(layers "F.Cu" "F.Mask" "F.Paste")
			(net "GND")
		)
		(pad "5" smd rect
			(at 2.232406 0.975106 270)
			(size 0.3556 1.4224)
			(layers "F.Cu" "F.Mask" "F.Paste")
			(net "Net_10762")
		)
		(pad "6" smd rect
			(at 2.232406 0.32512 270)
			(size 0.3556 1.4224)
			(layers "F.Cu" "F.Mask" "F.Paste")
			(net "I3C_BMC_SWB_R_SDA")
		)
		(pad "7" smd rect
			(at 2.232406 -0.32512 270)
			(size 0.3556 1.4224)
			(layers "F.Cu" "F.Mask" "F.Paste")
			(net "I3C_BMC_SWB_BUF_R_SDA")
		)
		(pad "8" smd rect
			(at 2.232406 -0.975106 270)
			(size 0.3556 1.4224)
			(layers "F.Cu" "F.Mask" "F.Paste")
			(net "P3V3_AUX")
		)
	)
	(footprint ""
		(layer "F.Cu")
		(at 102.268782 -380.385828)
		(property "Reference" "C710"
			(at 0 0 0)
			(layer "F.SilkS")
			(hide yes)
			(effects
				(font
					(size 1.27 1.27)
				)
			)
		)
		(property "Value" ""
			(at 0 0 0)
			(layer "F.Fab")
			(effects
				(font
					(size 1.27 1.27)
				)
			)
		)
		(duplicate_pad_numbers_are_jumpers no)
		(fp_line
			(start -0.299974 -0.150114)
			(end 0.299974 -0.150114)
			(stroke
				(width 0.1)
				(type default)
			)
			(layer "F.Fab")
		)
		(fp_line
			(start -0.299974 0.150114)
			(end -0.299974 -0.150114)
			(stroke
				(width 0.1)
				(type default)
			)
			(layer "F.Fab")
		)
		(fp_line
			(start 0.299974 -0.150114)
			(end 0.299974 0.150114)
			(stroke
				(width 0.1)
				(type default)
			)
			(layer "F.Fab")
		)
		(fp_line
			(start 0.299974 0.150114)
			(end -0.299974 0.150114)
			(stroke
				(width 0.1)
				(type default)
			)
			(layer "F.Fab")
		)
		(pad "1" smd rect
			(at -0.2667 0)
			(size 0.3048 0.381)
			(layers "F.Cu" "F.Mask" "F.Paste")
			(net "P5E_CPU1_P1_TX_C_DN<15>")
		)
		(pad "2" smd rect
			(at 0.2667 0)
			(size 0.3048 0.381)
			(layers "F.Cu" "F.Mask" "F.Paste")
			(net "P5E_CPU1_P1_TX_DN<15>")
		)
	)
)
